(kicad_pcb
	(version 20260206)
	(generator "pcbnew")
	(generator_version "10.0")
	(general
		(thickness 1.6)
		(legacy_teardrops no)
	)
	(paper "A4")
	(title_block
		(title "Bryce Canyon_F.DPB_16315-1-OCP.brd")
		(comment 1 "Bryce Canyon / footprints 1965-1969 of 2223")
	)
	(layers
		(0 "F.Cu" signal "TOP")
		(4 "In1.Cu" signal "L2GND")
		(6 "In2.Cu" signal "L3")
		(8 "In3.Cu" signal "L4GND")
		(10 "In4.Cu" signal "L5")
		(12 "In5.Cu" signal "L6VCC")
		(14 "In6.Cu" signal "L7VCC")
		(16 "In7.Cu" signal "L8")
		(18 "In8.Cu" signal "L9GND")
		(20 "In9.Cu" signal "L10")
		(22 "In10.Cu" signal "L11GND")
		(2 "B.Cu" signal "BOTTOM")
		(9 "F.Adhes" user "F.Adhesive")
		(11 "B.Adhes" user "B.Adhesive")
		(13 "F.Paste" user "Package Geometry/Pastemask Top")
		(15 "B.Paste" user "Package Geometry/Pastemask Bottom")
		(5 "F.SilkS" user "Ref Des/Silkscreen Top")
		(7 "B.SilkS" user "Ref Des/Silkscreen Bottom")
		(1 "F.Mask" user "Board Geometry/Soldermask Top")
		(3 "B.Mask" user "Board Geometry/Soldermask Bottom")
		(17 "Dwgs.User" user "User.Drawings")
		(19 "Cmts.User" user "User.Comments")
		(21 "Eco1.User" user "User.Eco1")
		(23 "Eco2.User" user "User.Eco2")
		(25 "Edge.Cuts" user "Board Geometry/Outline")
		(27 "Margin" user)
		(31 "F.CrtYd" user "Package Geometry/Place Bound Top")
		(29 "B.CrtYd" user "Package Geometry/Place Bound Bottom")
		(35 "F.Fab" user "Ref Des/Assembly Top")
		(33 "B.Fab" user "Ref Des/Assembly Bottom")
	)
	(footprint ""
		(layer "F.Cu")
		(at 114.725196 -283.736542 90)
		(property "Reference" "C88"
			(at 0 0 90)
			(layer "F.SilkS")
			(hide yes)
			(effects
				(font
					(size 1.27 1.27)
				)
			)
		)
		(property "Value" "SCD033U25V2KX-GP"
			(at 1.1811 -2.7051 90)
			(unlocked yes)
			(layer "F.Fab")
			(hide yes)
			(effects
				(font
					(size 1.016 1.016)
					(thickness 0.1524)
				)
			)
		)
		(property "Device Type" "C402H22"
			(at 1.1811 -4.2291 90)
			(unlocked yes)
			(layer "F.Fab")
			(hide yes)
			(effects
				(font
					(size 1.016 1.016)
					(thickness 0.1524)
				)
			)
		)
		(duplicate_pad_numbers_are_jumpers no)
		(fp_rect
			(start -0.4318 0.9525)
			(end 0.4318 -0.9525)
			(stroke
				(width 0)
				(type default)
			)
			(fill no)
			(layer "F.CrtYd")
		)
		(fp_rect
			(start -0.4318 0.9525)
			(end 0.4318 -0.9525)
			(stroke
				(width 0)
				(type default)
			)
			(fill no)
			(layer "F.Fab")
		)
		(pad "1" smd custom
			(at 0 -0.4445 90)
			(size 0.1524 0.1524)
			(layers "F.Cu" "F.Mask" "F.Paste")
			(net "P12V_A")
			(options
				(clearance outline)
				(anchor circle)
			)
			(primitives
				(gr_poly
					(pts
						(arc
							(start 0.3048 -0.2032)
							(mid 0.275042 -0.275042)
							(end 0.2032 -0.3048)
						)
						(arc
							(start -0.2032 -0.3048)
							(mid -0.275042 -0.275042)
							(end -0.3048 -0.2032)
						)
						(arc
							(start -0.3048 0.2032)
							(mid -0.275042 0.275042)
							(end -0.2032 0.3048)
						)
						(arc
							(start 0.2032 0.3048)
							(mid 0.275042 0.275042)
							(end 0.3048 0.2032)
						)
					)
					(width 0)
					(fill yes)
				)
			)
		)
		(pad "2" smd custom
			(at 0 0.4445 90)
			(size 0.1524 0.1524)
			(layers "F.Cu" "F.Mask" "F.Paste")
			(net "SW_HDD_N3")
			(options
				(clearance outline)
				(anchor circle)
			)
			(primitives
				(gr_poly
					(pts
						(arc
							(start 0.3048 -0.2032)
							(mid 0.275042 -0.275042)
							(end 0.2032 -0.3048)
						)
						(arc
							(start -0.2032 -0.3048)
							(mid -0.275042 -0.275042)
							(end -0.3048 -0.2032)
						)
						(arc
							(start -0.3048 0.2032)
							(mid -0.275042 0.275042)
							(end -0.2032 0.3048)
						)
						(arc
							(start 0.2032 0.3048)
							(mid 0.275042 0.275042)
							(end 0.3048 0.2032)
						)
					)
					(width 0)
					(fill yes)
				)
			)
		)
	)
	(footprint ""
		(layer "F.Cu")
		(at 241.427 -249.174)
		(property "Reference" "R49"
			(at 0 0 0)
			(layer "F.SilkS")
			(hide yes)
			(effects
				(font
					(size 1.27 1.27)
				)
			)
		)
		(property "Value" "4K7R2F-GP"
			(at 0.064008 -3.993896 0)
			(unlocked yes)
			(layer "F.Fab")
			(hide yes)
			(effects
				(font
					(size 1.016 1.016)
					(thickness 0.1524)
				)
			)
		)
		(property "Device Type" "R402H16"
			(at 0.064008 -5.517896 0)
			(unlocked yes)
			(layer "F.Fab")
			(hide yes)
			(effects
				(font
					(size 1.016 1.016)
					(thickness 0.1524)
				)
			)
		)
		(duplicate_pad_numbers_are_jumpers no)
		(fp_line
			(start -0.508 -0.9398)
			(end -0.508 0.9398)
			(stroke
				(width 0.1524)
				(type default)
			)
			(layer "F.SilkS")
		)
		(fp_line
			(start 0.508 -0.9398)
			(end -0.508 -0.9398)
			(stroke
				(width 0.1524)
				(type default)
			)
			(layer "F.SilkS")
		)
		(fp_rect
			(start -0.508 0.9398)
			(end 0.508 -0.9398)
			(stroke
				(width 0)
				(type default)
			)
			(fill no)
			(layer "F.CrtYd")
		)
		(fp_rect
			(start -0.508 0.9398)
			(end 0.508 -0.9398)
			(stroke
				(width 0)
				(type default)
			)
			(fill no)
			(layer "F.Fab")
		)
		(pad "1" smd custom
			(at 0 -0.4445)
			(size 0.1397 0.1397)
			(layers "F.Cu" "F.Mask" "F.Paste")
			(net "IO_EXP5_A1")
			(options
				(clearance outline)
				(anchor circle)
			)
			(primitives
				(gr_poly
					(pts
						(arc
							(start -0.1778 -0.2794)
							(mid -0.249642 -0.249642)
							(end -0.2794 -0.1778)
						)
						(arc
							(start -0.2794 0.1778)
							(mid -0.249642 0.249642)
							(end -0.1778 0.2794)
						)
						(arc
							(start 0.1778 0.2794)
							(mid 0.249642 0.249642)
							(end 0.2794 0.1778)
						)
						(arc
							(start 0.2794 -0.1778)
							(mid 0.249642 -0.249642)
							(end 0.1778 -0.2794)
						)
					)
					(width 0)
					(fill yes)
				)
			)
		)
		(pad "2" smd custom
			(at 0 0.4445)
			(size 0.1397 0.1397)
			(layers "F.Cu" "F.Mask" "F.Paste")
			(net "GND")
			(options
				(clearance outline)
				(anchor circle)
			)
			(primitives
				(gr_poly
					(pts
						(arc
							(start -0.1778 -0.2794)
							(mid -0.249642 -0.249642)
							(end -0.2794 -0.1778)
						)
						(arc
							(start -0.2794 0.1778)
							(mid -0.249642 0.249642)
							(end -0.1778 0.2794)
						)
						(arc
							(start 0.1778 0.2794)
							(mid 0.249642 0.249642)
							(end 0.2794 0.1778)
						)
						(arc
							(start 0.2794 -0.1778)
							(mid 0.249642 -0.249642)
							(end 0.1778 -0.2794)
						)
					)
					(width 0)
					(fill yes)
				)
			)
		)
	)
	(footprint ""
		(layer "F.Cu")
		(at 83.530948 -163.554918 180)
		(property "Reference" "Q85"
			(at 0 0 180)
			(layer "F.SilkS")
			(hide yes)
			(effects
				(font
					(size 1.27 1.27)
				)
			)
		)
		(property "Value" "2N7002KDW-GP"
			(at -2.3622 -8.2042 180)
			(unlocked yes)
			(layer "F.Fab")
			(hide yes)
			(effects
				(font
					(size 1.016 1.016)
					(thickness 0.1524)
				)
			)
		)
		(property "Device Type" "SOT-363H44"
			(at -2.3622 -10.1092 180)
			(unlocked yes)
			(layer "F.Fab")
			(hide yes)
			(effects
				(font
					(size 1.016 1.016)
					(thickness 0.1524)
				)
			)
		)
		(duplicate_pad_numbers_are_jumpers no)
		(fp_line
			(start 1.4478 1.7018)
			(end 1.4478 -1.7018)
			(stroke
				(width 0.1524)
				(type default)
			)
			(layer "F.SilkS")
		)
		(fp_line
			(start 1.4478 -1.7018)
			(end -1.4478 -1.7018)
			(stroke
				(width 0.1524)
				(type default)
			)
			(layer "F.SilkS")
		)
		(fp_line
			(start -1.27 1.524)
			(end -1.27 0.6604)
			(stroke
				(width 0.4826)
				(type default)
			)
			(layer "F.SilkS")
		)
		(fp_line
			(start -1.4478 1.7018)
			(end 1.4478 1.7018)
			(stroke
				(width 0.1524)
				(type default)
			)
			(layer "F.SilkS")
		)
		(fp_line
			(start -1.4478 -1.7018)
			(end -1.4478 1.7018)
			(stroke
				(width 0.1524)
				(type default)
			)
			(layer "F.SilkS")
		)
		(fp_poly
			(pts
				(xy -1.524 -1.778) (xy 1.524 -1.778) (xy 1.524 1.778) (xy -1.524 1.778)
			)
			(stroke
				(width 0)
				(type default)
			)
			(fill no)
			(layer "F.CrtYd")
		)
		(fp_poly
			(pts
				(xy -1.524 -1.778) (xy 1.524 -1.778) (xy 1.524 1.778) (xy -1.524 1.778)
			)
			(stroke
				(width 0)
				(type default)
			)
			(fill no)
			(layer "F.Fab")
		)
		(pad "1" smd rect
			(at -0.65024 0.9398 180)
			(size 0.4064 1.016)
			(layers "F.Cu" "F.Mask" "F.Paste")
			(net "GND")
		)
		(pad "2" smd rect
			(at 0 0.9398 180)
			(size 0.4064 1.016)
			(layers "F.Cu" "F.Mask" "F.Paste")
			(net "SW_PWR_R_HDD14")
		)
		(pad "3" smd rect
			(at 0.65024 0.9398 180)
			(size 0.4064 1.016)
			(layers "F.Cu" "F.Mask" "F.Paste")
			(net "SW_HDD_P14")
		)
		(pad "4" smd rect
			(at 0.65024 -0.9398 180)
			(size 0.4064 1.016)
			(layers "F.Cu" "F.Mask" "F.Paste")
			(net "GND")
		)
		(pad "5" smd rect
			(at 0 -0.9398 180)
			(size 0.4064 1.016)
			(layers "F.Cu" "F.Mask" "F.Paste")
			(net "SW_HDD_G14")
		)
		(pad "6" smd rect
			(at -0.65024 -0.9398 180)
			(size 0.4064 1.016)
			(layers "F.Cu" "F.Mask" "F.Paste")
			(net "SW_HDD_R14")
		)
	)
	(footprint ""
		(layer "F.Cu")
		(at 112.450118 -209.399886)
		(property "Reference" "FLED4"
			(at 0 0 0)
			(layer "F.SilkS")
			(hide yes)
			(effects
				(font
					(size 1.27 1.27)
				)
			)
		)
		(property "Value" "LED-BY-19-GP"
			(at -2.132076 1.414018 0)
			(unlocked yes)
			(layer "F.Fab")
			(hide yes)
			(effects
				(font
					(size 1.016 1.016)
					(thickness 0.1524)
				)
			)
		)
		(property "Device Type" "LED-1615-4PH26"
			(at -2.132076 -0.109982 0)
			(unlocked yes)
			(layer "F.Fab")
			(hide yes)
			(effects
				(font
					(size 1.016 1.016)
					(thickness 0.1524)
				)
			)
		)
		(duplicate_pad_numbers_are_jumpers no)
		(fp_line
			(start -1.2954 0.254)
			(end -1.2954 1.6002)
			(stroke
				(width 0.508)
				(type default)
			)
			(layer "F.SilkS")
		)
		(fp_line
			(start -1.2954 1.6002)
			(end 1.2954 1.6002)
			(stroke
				(width 0.508)
				(type default)
			)
			(layer "F.SilkS")
		)
		(fp_line
			(start -1.1176 -1.4224)
			(end 1.1176 -1.4224)
			(stroke
				(width 0.1524)
				(type default)
			)
			(layer "F.SilkS")
		)
		(fp_line
			(start -1.1176 1.4224)
			(end -1.1176 -1.4224)
			(stroke
				(width 0.1524)
				(type default)
			)
			(layer "F.SilkS")
		)
		(fp_line
			(start 1.1176 -1.4224)
			(end 1.1176 1.4224)
			(stroke
				(width 0.1524)
				(type default)
			)
			(layer "F.SilkS")
		)
		(fp_line
			(start 1.1176 1.4224)
			(end -1.1176 1.4224)
			(stroke
				(width 0.1524)
				(type default)
			)
			(layer "F.SilkS")
		)
		(fp_line
			(start 1.2954 1.6002)
			(end 1.2954 0.254)
			(stroke
				(width 0.508)
				(type default)
			)
			(layer "F.SilkS")
		)
		(fp_rect
			(start -0.7493 0.8001)
			(end 0.7493 -0.8001)
			(stroke
				(width 0)
				(type default)
			)
			(fill no)
			(layer "F.CrtYd")
		)
		(fp_poly
			(pts
				(xy -1.3716 1.6764) (xy -1.3716 -1.6764) (xy 1.3716 -1.6764) (xy 1.3716 0.0635) (xy 0.7493 0.0635)
				(xy 0.7493 -0.8001) (xy -0.7493 -0.8001) (xy -0.7493 0.8001) (xy 0.7493 0.8001) (xy 0.7493 0.0762)
				(xy 1.3716 0.0762) (xy 1.3716 1.6764)
			)
			(stroke
				(width 0)
				(type default)
			)
			(fill no)
			(layer "F.CrtYd")
		)
		(fp_rect
			(start -1.3716 1.6764)
			(end 1.3716 -1.6764)
			(stroke
				(width 0)
				(type default)
			)
			(fill no)
			(layer "F.Fab")
		)
		(pad "1" smd rect
			(at 0.50038 -0.73025)
			(size 0.7112 0.8636)
			(layers "F.Cu" "F.Mask" "F.Paste")
			(net "DRV_ACT_3")
		)
		(pad "2" smd rect
			(at -0.50038 -0.73025)
			(size 0.7112 0.8636)
			(layers "F.Cu" "F.Mask" "F.Paste")
			(net "FLT_HDD3")
		)
		(pad "3" smd rect
			(at 0.50038 0.73025)
			(size 0.7112 0.8636)
			(layers "F.Cu" "F.Mask" "F.Paste")
			(net "DRV_ACT_3_N")
		)
		(pad "4" smd rect
			(at -0.50038 0.73025)
			(size 0.7112 0.8636)
			(layers "F.Cu" "F.Mask" "F.Paste")
			(net "FLT_HDD3_N")
		)
	)
	(footprint ""
		(layer "F.Cu")
		(at 375.16181 -242.799108 180)
		(property "Reference" "Q235"
			(at 0 0 180)
			(layer "F.SilkS")
			(hide yes)
			(effects
				(font
					(size 1.27 1.27)
				)
			)
		)
		(property "Value" "2N7002K-2-GP"
			(at 0.127 -8.9662 180)
			(unlocked yes)
			(layer "F.Fab")
			(hide yes)
			(effects
				(font
					(size 1.016 1.016)
					(thickness 0.1524)
				)
			)
		)
		(property "Device Type" "SOT23DGS2D4H44"
			(at 0.127 -10.4902 180)
			(unlocked yes)
			(layer "F.Fab")
			(hide yes)
			(effects
				(font
					(size 1.016 1.016)
					(thickness 0.1524)
				)
			)
		)
		(duplicate_pad_numbers_are_jumpers no)
		(fp_line
			(start 1.651 1.778)
			(end 1.651 -1.778)
			(stroke
				(width 0.1524)
				(type default)
			)
			(layer "F.SilkS")
		)
		(fp_line
			(start 1.651 -1.778)
			(end -1.651 -1.778)
			(stroke
				(width 0.1524)
				(type default)
			)
			(layer "F.SilkS")
		)
		(fp_line
			(start -1.651 1.778)
			(end 1.651 1.778)
			(stroke
				(width 0.1524)
				(type default)
			)
			(layer "F.SilkS")
		)
		(fp_line
			(start -1.651 -1.778)
			(end -1.651 1.778)
			(stroke
				(width 0.1524)
				(type default)
			)
			(layer "F.SilkS")
		)
		(fp_poly
			(pts
				(xy -1.778 1.8796) (xy -1.778 -1.8796) (xy 1.778 -1.8796) (xy 1.778 1.8796)
			)
			(stroke
				(width 0)
				(type default)
			)
			(fill no)
			(layer "F.CrtYd")
		)
		(fp_poly
			(pts
				(xy -1.778 1.8796) (xy -1.778 -1.8796) (xy 1.778 -1.8796) (xy 1.778 1.8796)
			)
			(stroke
				(width 0)
				(type default)
			)
			(fill no)
			(layer "F.Fab")
		)
		(pad "D" smd custom
			(at 0 -0.9525 180)
			(size 0.1905 0.1905)
			(layers "F.Cu" "F.Mask" "F.Paste")
			(net "FLT_HDD8_N")
			(options
				(clearance outline)
				(anchor circle)
			)
			(primitives
				(gr_poly
					(pts
						(arc
							(start -0.1778 0.5715)
							(mid -0.321484 0.511984)
							(end -0.381 0.3683)
						)
						(arc
							(start -0.381 -0.3683)
							(mid -0.321484 -0.511984)
							(end -0.1778 -0.5715)
						)
						(arc
							(start 0.1778 -0.5715)
							(mid 0.321484 -0.511984)
							(end 0.381 -0.3683)
						)
						(arc
							(start 0.381 0.3683)
							(mid 0.321484 0.511984)
							(end 0.1778 0.5715)
						)
					)
					(width 0)
					(fill yes)
				)
			)
		)
		(pad "G" smd custom
			(at -0.98425 0.9525 180)
			(size 0.1905 0.1905)
			(layers "F.Cu" "F.Mask" "F.Paste")
			(net "DRIVE_A_8_FLT_LED")
			(options
				(clearance outline)
				(anchor circle)
			)
			(primitives
				(gr_poly
					(pts
						(arc
							(start -0.1778 0.5715)
							(mid -0.321484 0.511984)
							(end -0.381 0.3683)
						)
						(arc
							(start -0.381 -0.3683)
							(mid -0.321484 -0.511984)
							(end -0.1778 -0.5715)
						)
						(arc
							(start 0.1778 -0.5715)
							(mid 0.321484 -0.511984)
							(end 0.381 -0.3683)
						)
						(arc
							(start 0.381 0.3683)
							(mid 0.321484 0.511984)
							(end 0.1778 0.5715)
						)
					)
					(width 0)
					(fill yes)
				)
			)
		)
		(pad "S" smd custom
			(at 0.98425 0.9525 180)
			(size 0.1905 0.1905)
			(layers "F.Cu" "F.Mask" "F.Paste")
			(net "GND")
			(options
				(clearance outline)
				(anchor circle)
			)
			(primitives
				(gr_poly
					(pts
						(arc
							(start -0.1778 0.5715)
							(mid -0.321484 0.511984)
							(end -0.381 0.3683)
						)
						(arc
							(start -0.381 -0.3683)
							(mid -0.321484 -0.511984)
							(end -0.1778 -0.5715)
						)
						(arc
							(start 0.1778 -0.5715)
							(mid 0.321484 -0.511984)
							(end 0.381 -0.3683)
						)
						(arc
							(start 0.381 0.3683)
							(mid 0.321484 0.511984)
							(end 0.1778 0.5715)
						)
					)
					(width 0)
					(fill yes)
				)
			)
		)
	)
)
